%FSTAX23Y23*%
%MOIN*%
%SFA1B1*%

%IPPOS*%
%ADD50R,0.028000X0.165000*%
%ADD51R,0.028000X0.126000*%
%ADD62R,0.057090X0.045280*%
%ADD64R,0.025200X0.026770*%
%ADD71R,0.045280X0.057090*%
%ADD72R,0.026770X0.025200*%
%ADD77R,0.082870X0.044090*%
%LNgrandmaster-1*%
%LPD*%
G54D50*
X01915Y00137D03*
X02545D03*
X02624D03*
X02899D03*
X03057D03*
X02742D03*
X02938D03*
X02781D03*
X02309D03*
X02427D03*
X02584D03*
X02072D03*
X02033D03*
X01994D03*
X01954D03*
X0219D03*
X02348D03*
X02387D03*
X02466D03*
X02505D03*
X0282D03*
X02663D03*
X0286D03*
X02978D03*
X03017D03*
X02702D03*
X02112D03*
X02151D03*
X01836D03*
X01875D03*
X03096D03*
G54D51*
X01797Y00157D03*
G54D62*
X02632Y02971D03*
Y03042D03*
G54D64*
X02349Y00329D03*
Y00362D03*
X02389D03*
Y00329D03*
X02468D03*
Y00362D03*
X02511D03*
Y00329D03*
X02664Y00362D03*
Y00329D03*
X02704Y00362D03*
Y00329D03*
X02819Y00362D03*
Y00329D03*
X02854D03*
Y00362D03*
X02979D03*
Y00329D03*
X03019Y00362D03*
Y00329D03*
X02711Y03003D03*
Y03036D03*
G54D71*
X02398Y02944D03*
X02327D03*
G54D72*
X02385Y02854D03*
X02351D03*
G54D77*
X02334Y03279D03*
Y032D03*
Y03121D03*
Y03042D03*
X02509Y03279D03*
Y03121D03*
Y032D03*
Y03042D03*
M02*